# T6G (Grand Teton) — schematic netlist excerpt (pin names and nets, part order shuffled) for the footprints in the layout excerpt that follows; sources: Cadence DE-HDL packaged netlist, KiCad conversion of 04192023_DAF0TMB3IC0_F0TG_MB_C_brd_V02_OCP.brd

R6130  Q_RES  1K 1% CHIP  pkg 0402LF  page 84 : A = PVDD18_S5_P0 ; B = FAB_REV_ID2
C1104  Q_CAP  0.1UF 25V 10% X7R  pkg 0402  page 77 : A = P3V3_AUX ; B = GND

(kicad_pcb
	(version 20260206)
	(generator "pcbnew")
	(generator_version "10.0")
	(general
		(thickness 1.6)
		(legacy_teardrops no)
	)
	(paper "A4")
	(title_block
		(title "04192023_DAF0TMB3IC0_F0TG_MB_C_brd_V02_OCP.brd")
		(comment 1 "Grand Teton / footprints 6111-6112 of 8354")
	)
	(layers
		(0 "F.Cu" signal "TOP")
		(4 "In1.Cu" signal "GND")
		(6 "In2.Cu" signal "IN1")
		(8 "In3.Cu" signal "GND1")
		(10 "In4.Cu" signal "IN2")
		(12 "In5.Cu" signal "GND2")
		(14 "In6.Cu" signal "IN3")
		(16 "In7.Cu" signal "GND3")
		(18 "In8.Cu" signal "VCC")
		(20 "In9.Cu" signal "VCC1")
		(22 "In10.Cu" signal "GND4")
		(24 "In11.Cu" signal "IN4")
		(26 "In12.Cu" signal "GND5")
		(28 "In13.Cu" signal "IN5")
		(30 "In14.Cu" signal "GND6")
		(32 "In15.Cu" signal "IN6")
		(34 "In16.Cu" signal "GND7")
		(2 "B.Cu" signal "BOTTOM")
		(9 "F.Adhes" user "F.Adhesive")
		(11 "B.Adhes" user "B.Adhesive")
		(13 "F.Paste" user "Package Geometry/Pastemask Top")
		(15 "B.Paste" user "Package Geometry/Pastemask Bottom")
		(5 "F.SilkS" user "Ref Des/Silkscreen Top")
		(7 "B.SilkS" user "Ref Des/Silkscreen Bottom")
		(1 "F.Mask" user "Board Geometry/Soldermask Top")
		(3 "B.Mask" user "Board Geometry/Soldermask Bottom")
		(17 "Dwgs.User" user "User.Drawings")
		(19 "Cmts.User" user "User.Comments")
		(21 "Eco1.User" user "User.Eco1")
		(23 "Eco2.User" user "User.Eco2")
		(25 "Edge.Cuts" user "Board Geometry/Outline")
		(27 "Margin" user)
		(31 "F.CrtYd" user "Package Geometry/Place Bound Top")
		(29 "B.CrtYd" user "Package Geometry/Place Bound Bottom")
		(35 "F.Fab" user "Ref Des/Assembly Top")
		(33 "B.Fab" user "Ref Des/Assembly Bottom")
	)
	(footprint ""
		(layer "B.Cu")
		(at 257.379724 -132.625084 -90)
		(property "Reference" "C1104"
			(at 0 0 90)
			(layer "B.SilkS")
			(hide yes)
			(effects
				(font
					(size 1.27 1.27)
				)
				(justify mirror)
			)
		)
		(property "Value" ""
			(at 0 0 90)
			(layer "B.Fab")
			(effects
				(font
					(size 1.27 1.27)
				)
				(justify mirror)
			)
		)
		(duplicate_pad_numbers_are_jumpers no)
		(fp_line
			(start -0.7874 0.4064)
			(end 0.7874 0.4064)
			(stroke
				(width 0.1524)
				(type default)
			)
			(layer "B.SilkS")
		)
		(fp_line
			(start 0.7874 0.4064)
			(end 0.7874 -0.4064)
			(stroke
				(width 0.1524)
				(type default)
			)
			(layer "B.SilkS")
		)
		(fp_line
			(start -0.7874 -0.4064)
			(end -0.7874 0.4064)
			(stroke
				(width 0.1524)
				(type default)
			)
			(layer "B.SilkS")
		)
		(fp_line
			(start 0.7874 -0.4064)
			(end -0.7874 -0.4064)
			(stroke
				(width 0.1524)
				(type default)
			)
			(layer "B.SilkS")
		)
		(fp_line
			(start -0.67945 0.3048)
			(end -0.120396 0.3048)
			(stroke
				(width 0.1)
				(type default)
			)
			(layer "B.Fab")
		)
		(fp_line
			(start -0.120396 0.3048)
			(end -0.120396 0.2794)
			(stroke
				(width 0.1)
				(type default)
			)
			(layer "B.Fab")
		)
		(fp_line
			(start 0.12065 0.3048)
			(end 0.67945 0.3048)
			(stroke
				(width 0.1)
				(type default)
			)
			(layer "B.Fab")
		)
		(fp_line
			(start 0.67945 0.3048)
			(end 0.67945 -0.305054)
			(stroke
				(width 0.1)
				(type default)
			)
			(layer "B.Fab")
		)
		(fp_line
			(start -0.120396 0.2794)
			(end 0.12065 0.2794)
			(stroke
				(width 0.1)
				(type default)
			)
			(layer "B.Fab")
		)
		(fp_line
			(start 0.12065 0.2794)
			(end 0.12065 0.3048)
			(stroke
				(width 0.1)
				(type default)
			)
			(layer "B.Fab")
		)
		(fp_line
			(start -0.12065 -0.2794)
			(end -0.12065 -0.3048)
			(stroke
				(width 0.1)
				(type default)
			)
			(layer "B.Fab")
		)
		(fp_line
			(start 0.12065 -0.2794)
			(end -0.12065 -0.2794)
			(stroke
				(width 0.1)
				(type default)
			)
			(layer "B.Fab")
		)
		(fp_line
			(start -0.67945 -0.3048)
			(end -0.67945 0.3048)
			(stroke
				(width 0.1)
				(type default)
			)
			(layer "B.Fab")
		)
		(fp_line
			(start -0.12065 -0.3048)
			(end -0.67945 -0.3048)
			(stroke
				(width 0.1)
				(type default)
			)
			(layer "B.Fab")
		)
		(fp_line
			(start 0.12065 -0.305054)
			(end 0.12065 -0.2794)
			(stroke
				(width 0.1)
				(type default)
			)
			(layer "B.Fab")
		)
		(fp_line
			(start 0.67945 -0.305054)
			(end 0.12065 -0.305054)
			(stroke
				(width 0.1)
				(type default)
			)
			(layer "B.Fab")
		)
		(pad "1" smd circle
			(at 0.40005 0 90)
			(size 0 0)
			(layers "B.Cu" "B.Mask" "B.Paste")
			(net "P3V3_AUX")
		)
		(pad "2" smd circle
			(at -0.40005 0 90)
			(size 0 0)
			(layers "B.Cu" "B.Mask" "B.Paste")
			(net "GND")
		)
	)
	(footprint ""
		(layer "B.Cu")
		(at 393.381484 -204.249782)
		(property "Reference" "R6130"
			(at 0 0 0)
			(layer "B.SilkS")
			(hide yes)
			(effects
				(font
					(size 1.27 1.27)
				)
				(justify mirror)
			)
		)
		(property "Value" ""
			(at 0 0 0)
			(layer "B.Fab")
			(effects
				(font
					(size 1.27 1.27)
				)
				(justify mirror)
			)
		)
		(duplicate_pad_numbers_are_jumpers no)
		(fp_line
			(start -0.7874 -0.4064)
			(end -0.7874 0.4064)
			(stroke
				(width 0.1524)
				(type default)
			)
			(layer "B.SilkS")
		)
		(fp_line
			(start -0.7874 0.4064)
			(end 0.7874 0.4064)
			(stroke
				(width 0.1524)
				(type default)
			)
			(layer "B.SilkS")
		)
		(fp_line
			(start 0.7874 -0.4064)
			(end -0.7874 -0.4064)
			(stroke
				(width 0.1524)
				(type default)
			)
			(layer "B.SilkS")
		)
		(fp_line
			(start 0.7874 0.4064)
			(end 0.7874 -0.4064)
			(stroke
				(width 0.1524)
				(type default)
			)
			(layer "B.SilkS")
		)
		(fp_line
			(start -0.67945 -0.3048)
			(end -0.67945 0.3048)
			(stroke
				(width 0.1)
				(type default)
			)
			(layer "B.Fab")
		)
		(fp_line
			(start -0.67945 0.3048)
			(end -0.120396 0.3048)
			(stroke
				(width 0.1)
				(type default)
			)
			(layer "B.Fab")
		)
		(fp_line
			(start -0.12065 -0.3048)
			(end -0.67945 -0.3048)
			(stroke
				(width 0.1)
				(type default)
			)
			(layer "B.Fab")
		)
		(fp_line
			(start -0.12065 -0.2794)
			(end -0.12065 -0.3048)
			(stroke
				(width 0.1)
				(type default)
			)
			(layer "B.Fab")
		)
		(fp_line
			(start -0.120396 0.2794)
			(end 0.12065 0.2794)
			(stroke
				(width 0.1)
				(type default)
			)
			(layer "B.Fab")
		)
		(fp_line
			(start -0.120396 0.3048)
			(end -0.120396 0.2794)
			(stroke
				(width 0.1)
				(type default)
			)
			(layer "B.Fab")
		)
		(fp_line
			(start 0.12065 -0.305054)
			(end 0.12065 -0.2794)
			(stroke
				(width 0.1)
				(type default)
			)
			(layer "B.Fab")
		)
		(fp_line
			(start 0.12065 -0.2794)
			(end -0.12065 -0.2794)
			(stroke
				(width 0.1)
				(type default)
			)
			(layer "B.Fab")
		)
		(fp_line
			(start 0.12065 0.2794)
			(end 0.12065 0.3048)
			(stroke
				(width 0.1)
				(type default)
			)
			(layer "B.Fab")
		)
		(fp_line
			(start 0.12065 0.3048)
			(end 0.67945 0.3048)
			(stroke
				(width 0.1)
				(type default)
			)
			(layer "B.Fab")
		)
		(fp_line
			(start 0.67945 -0.305054)
			(end 0.12065 -0.305054)
			(stroke
				(width 0.1)
				(type default)
			)
			(layer "B.Fab")
		)
		(fp_line
			(start 0.67945 0.3048)
			(end 0.67945 -0.305054)
			(stroke
				(width 0.1)
				(type default)
			)
			(layer "B.Fab")
		)
		(pad "1" smd circle
			(at 0.40005 0 180)
			(size 0 0)
			(layers "B.Cu" "B.Mask" "B.Paste")
			(net "PVDD18_S5_P0")
		)
		(pad "2" smd circle
			(at -0.40005 0 180)
			(size 0 0)
			(layers "B.Cu" "B.Mask" "B.Paste")
			(net "FAB_REV_ID2")
		)
	)
)
